# BASEBOARD_FAB2 (Tioga Pass) — schematic netlist excerpt (pin names and nets, part order shuffled) for the footprints in the layout excerpt that follows; sources: Cadence DE-HDL packaged netlist, KiCad conversion of Wiwynn_Tioga_Pass_MB.brd

R1D34  RES  16K 1.0% CHIP  pkg 0402  page 199 : A = A_HSC_ISTART ; B = AGND_HSC
R8F29  RES  33.2 1% CHIP  pkg 0402  page 101 : A = CLK_25M_BMC_R ; B = CLK_25M_BMC
R1C28  RES  1.00K 1% CHIP  pkg 0402  page 206 : A = P3V3_STBY ; B = VR_VRRDY_PVCCIN_CPU1

(kicad_pcb
	(version 20260206)
	(generator "pcbnew")
	(generator_version "10.0")
	(general
		(thickness 1.6)
		(legacy_teardrops no)
	)
	(paper "A4")
	(title_block
		(title "Wiwynn_Tioga_Pass_MB.brd")
		(comment 1 "Tioga Pass / footprints 1049-1051 of 4770")
	)
	(layers
		(0 "F.Cu" signal "TOP")
		(4 "In1.Cu" signal "L2GND")
		(6 "In2.Cu" signal "L3")
		(8 "In3.Cu" signal "L4GND")
		(10 "In4.Cu" signal "L5")
		(12 "In5.Cu" signal "L6GND")
		(14 "In6.Cu" signal "L7VCC")
		(16 "In7.Cu" signal "L8VCC")
		(18 "In8.Cu" signal "L9GND")
		(20 "In9.Cu" signal "L10")
		(22 "In10.Cu" signal "L11GND")
		(24 "In11.Cu" signal "L12")
		(26 "In12.Cu" signal "L13GND")
		(2 "B.Cu" signal "BOTTOM")
		(9 "F.Adhes" user "F.Adhesive")
		(11 "B.Adhes" user "B.Adhesive")
		(13 "F.Paste" user "Package Geometry/Pastemask Top")
		(15 "B.Paste" user "Package Geometry/Pastemask Bottom")
		(5 "F.SilkS" user "Ref Des/Silkscreen Top")
		(7 "B.SilkS" user "Ref Des/Silkscreen Bottom")
		(1 "F.Mask" user "Board Geometry/Soldermask Top")
		(3 "B.Mask" user "Board Geometry/Soldermask Bottom")
		(17 "Dwgs.User" user "User.Drawings")
		(19 "Cmts.User" user "User.Comments")
		(21 "Eco1.User" user "User.Eco1")
		(23 "Eco2.User" user "User.Eco2")
		(25 "Edge.Cuts" user "Board Geometry/Outline")
		(27 "Margin" user)
		(31 "F.CrtYd" user "Package Geometry/Place Bound Top")
		(29 "B.CrtYd" user "Package Geometry/Place Bound Bottom")
		(35 "F.Fab" user "Ref Des/Assembly Top")
		(33 "B.Fab" user "Ref Des/Assembly Bottom")
	)
	(footprint ""
		(layer "F.Cu")
		(at 482.67366 -30.29712 90)
		(property "Reference" "R8F29"
			(at 0 0 90)
			(layer "F.SilkS")
			(hide yes)
			(effects
				(font
					(size 1.27 1.27)
				)
			)
		)
		(property "Value" ""
			(at 0 0 90)
			(layer "F.Fab")
			(effects
				(font
					(size 1.27 1.27)
				)
			)
		)
		(duplicate_pad_numbers_are_jumpers no)
		(fp_poly
			(pts
				(xy -0.2794 -0.1016) (xy 0.2794 -0.1016) (xy 0.2794 0.9906) (xy -0.2794 0.9906)
			)
			(stroke
				(width 0)
				(type default)
			)
			(fill no)
			(layer "F.CrtYd")
		)
		(fp_line
			(start 0.2794 -0.1016)
			(end -0.2794 -0.1016)
			(stroke
				(width 0.1)
				(type default)
			)
			(layer "F.Fab")
		)
		(fp_line
			(start -0.2794 -0.1016)
			(end -0.2794 0.9906)
			(stroke
				(width 0.1)
				(type default)
			)
			(layer "F.Fab")
		)
		(fp_line
			(start 0.2794 0.9906)
			(end 0.2794 -0.1016)
			(stroke
				(width 0.1)
				(type default)
			)
			(layer "F.Fab")
		)
		(fp_line
			(start -0.2794 0.9906)
			(end 0.2794 0.9906)
			(stroke
				(width 0.1)
				(type default)
			)
			(layer "F.Fab")
		)
		(pad "1" smd rect
			(at 0 0 90)
			(size 0.508 0.508)
			(layers "F.Cu" "F.Mask" "F.Paste")
			(net "CLK_25M_BMC_R")
		)
		(pad "2" smd rect
			(at 0 0.889 90)
			(size 0.508 0.508)
			(layers "F.Cu" "F.Mask" "F.Paste")
			(net "CLK_25M_BMC")
		)
		(zone
			(layer "F.Cu")
			(hatch none 0.5)
			(connect_pads
				(clearance 0)
			)
			(min_thickness 0.25)
			(keepout
				(tracks allowed)
				(vias not_allowed)
				(pads allowed)
				(copperpour not_allowed)
				(footprints allowed)
			)
			(placement
				(enabled no)
				(sheetname "")
			)
			(fill
				(thermal_gap 0.5)
				(thermal_bridge_width 0.5)
				(island_removal_mode 0)
			)
			(polygon
				(pts
					(xy 482.92766 -30.04312) (xy 482.92766 -30.55112) (xy 483.30866 -30.55112) (xy 483.30866 -30.04312)
				)
			)
		)
		(zone
			(layer "F.Cu")
			(hatch none 0.5)
			(connect_pads
				(clearance 0)
			)
			(min_thickness 0.25)
			(keepout
				(tracks not_allowed)
				(vias allowed)
				(pads allowed)
				(copperpour not_allowed)
				(footprints allowed)
			)
			(placement
				(enabled no)
				(sheetname "")
			)
			(fill
				(thermal_gap 0.5)
				(thermal_bridge_width 0.5)
				(island_removal_mode 0)
			)
			(polygon
				(pts
					(xy 483.30866 -30.04312) (xy 483.30866 -30.55112) (xy 482.92766 -30.55112) (xy 482.92766 -30.04312)
				)
			)
		)
	)
	(footprint ""
		(layer "F.Cu")
		(at 22.225 -75.438 90)
		(property "Reference" "R1D34"
			(at 0 0 90)
			(layer "F.SilkS")
			(hide yes)
			(effects
				(font
					(size 1.27 1.27)
				)
			)
		)
		(property "Value" ""
			(at 0 0 90)
			(layer "F.Fab")
			(effects
				(font
					(size 1.27 1.27)
				)
			)
		)
		(duplicate_pad_numbers_are_jumpers no)
		(fp_poly
			(pts
				(xy -0.2794 -0.1016) (xy 0.2794 -0.1016) (xy 0.2794 0.9906) (xy -0.2794 0.9906)
			)
			(stroke
				(width 0)
				(type default)
			)
			(fill no)
			(layer "F.CrtYd")
		)
		(fp_line
			(start 0.2794 -0.1016)
			(end -0.2794 -0.1016)
			(stroke
				(width 0.1)
				(type default)
			)
			(layer "F.Fab")
		)
		(fp_line
			(start -0.2794 -0.1016)
			(end -0.2794 0.9906)
			(stroke
				(width 0.1)
				(type default)
			)
			(layer "F.Fab")
		)
		(fp_line
			(start 0.2794 0.9906)
			(end 0.2794 -0.1016)
			(stroke
				(width 0.1)
				(type default)
			)
			(layer "F.Fab")
		)
		(fp_line
			(start -0.2794 0.9906)
			(end 0.2794 0.9906)
			(stroke
				(width 0.1)
				(type default)
			)
			(layer "F.Fab")
		)
		(pad "1" smd rect
			(at 0 0 90)
			(size 0.508 0.508)
			(layers "F.Cu" "F.Mask" "F.Paste")
			(net "A_HSC_ISTART")
		)
		(pad "2" smd rect
			(at 0 0.889 90)
			(size 0.508 0.508)
			(layers "F.Cu" "F.Mask" "F.Paste")
			(net "AGND_HSC")
		)
		(zone
			(layer "F.Cu")
			(hatch none 0.5)
			(connect_pads
				(clearance 0)
			)
			(min_thickness 0.25)
			(keepout
				(tracks allowed)
				(vias not_allowed)
				(pads allowed)
				(copperpour not_allowed)
				(footprints allowed)
			)
			(placement
				(enabled no)
				(sheetname "")
			)
			(fill
				(thermal_gap 0.5)
				(thermal_bridge_width 0.5)
				(island_removal_mode 0)
			)
			(polygon
				(pts
					(xy 22.479 -75.184) (xy 22.479 -75.692) (xy 22.86 -75.692) (xy 22.86 -75.184)
				)
			)
		)
		(zone
			(layer "F.Cu")
			(hatch none 0.5)
			(connect_pads
				(clearance 0)
			)
			(min_thickness 0.25)
			(keepout
				(tracks not_allowed)
				(vias allowed)
				(pads allowed)
				(copperpour not_allowed)
				(footprints allowed)
			)
			(placement
				(enabled no)
				(sheetname "")
			)
			(fill
				(thermal_gap 0.5)
				(thermal_bridge_width 0.5)
				(island_removal_mode 0)
			)
			(polygon
				(pts
					(xy 22.86 -75.184) (xy 22.86 -75.692) (xy 22.479 -75.692) (xy 22.479 -75.184)
				)
			)
		)
	)
	(footprint ""
		(layer "F.Cu")
		(at 13.843 -89.281 90)
		(property "Reference" "R1C28"
			(at 0 0 90)
			(layer "F.SilkS")
			(hide yes)
			(effects
				(font
					(size 1.27 1.27)
				)
			)
		)
		(property "Value" ""
			(at 0 0 90)
			(layer "F.Fab")
			(effects
				(font
					(size 1.27 1.27)
				)
			)
		)
		(duplicate_pad_numbers_are_jumpers no)
		(fp_rect
			(start -0.2794 -0.1016)
			(end 0.2794 0.9906)
			(stroke
				(width 0)
				(type default)
			)
			(fill no)
			(layer "F.CrtYd")
		)
		(fp_line
			(start 0.2794 -0.1016)
			(end -0.2794 -0.1016)
			(stroke
				(width 0.1)
				(type default)
			)
			(layer "F.Fab")
		)
		(fp_line
			(start -0.2794 -0.1016)
			(end -0.2794 0.9906)
			(stroke
				(width 0.1)
				(type default)
			)
			(layer "F.Fab")
		)
		(fp_line
			(start 0.2794 0.9906)
			(end 0.2794 -0.1016)
			(stroke
				(width 0.1)
				(type default)
			)
			(layer "F.Fab")
		)
		(fp_line
			(start -0.2794 0.9906)
			(end 0.2794 0.9906)
			(stroke
				(width 0.1)
				(type default)
			)
			(layer "F.Fab")
		)
		(pad "1" smd rect
			(at 0 0 90)
			(size 0.508 0.508)
			(layers "F.Cu" "F.Mask" "F.Paste")
			(net "P3V3_STBY")
		)
		(pad "2" smd rect
			(at 0 0.889 90)
			(size 0.508 0.508)
			(layers "F.Cu" "F.Mask" "F.Paste")
			(net "VR_VRRDY_PVCCIN_CPU1")
		)
		(zone
			(layer "F.Cu")
			(hatch none 0.5)
			(connect_pads
				(clearance 0)
			)
			(min_thickness 0.25)
			(keepout
				(tracks not_allowed)
				(vias allowed)
				(pads allowed)
				(copperpour not_allowed)
				(footprints allowed)
			)
			(placement
				(enabled no)
				(sheetname "")
			)
			(fill
				(thermal_gap 0.5)
				(thermal_bridge_width 0.5)
				(island_removal_mode 0)
			)
			(polygon
				(pts
					(xy 14.097 -89.027) (xy 14.478 -89.027) (xy 14.478 -89.535) (xy 14.097 -89.535)
				)
			)
		)
		(zone
			(layer "F.Cu")
			(hatch none 0.5)
			(connect_pads
				(clearance 0)
			)
			(min_thickness 0.25)
			(keepout
				(tracks allowed)
				(vias not_allowed)
				(pads allowed)
				(copperpour not_allowed)
				(footprints allowed)
			)
			(placement
				(enabled no)
				(sheetname "")
			)
			(fill
				(thermal_gap 0.5)
				(thermal_bridge_width 0.5)
				(island_removal_mode 0)
			)
			(polygon
				(pts
					(xy 14.097 -89.027) (xy 14.478 -89.027) (xy 14.478 -89.535) (xy 14.097 -89.535)
				)
			)
		)
	)
)
